(kicad_pcb
	(version 20260206)
	(generator "pcbnew")
	(generator_version "10.0")
	(general
		(thickness 1.6)
		(legacy_teardrops no)
	)
	(paper "A4")
	(title_block
		(title "v1-pdb — T6M_PDB_D_0927_0900.brd")
		(comment 1 "Open CloudServer (Microsoft) / footprints 210-214 of 321")
	)
	(layers
		(0 "F.Cu" signal "TOP")
		(4 "In1.Cu" signal "GND")
		(6 "In2.Cu" signal "IN1")
		(8 "In3.Cu" signal "VCC")
		(10 "In4.Cu" signal "VCC1")
		(12 "In5.Cu" signal "IN2")
		(14 "In6.Cu" signal "GND1")
		(2 "B.Cu" signal "BOTTOM")
		(9 "F.Adhes" user "F.Adhesive")
		(11 "B.Adhes" user "B.Adhesive")
		(13 "F.Paste" user "Package Geometry/Pastemask Top")
		(15 "B.Paste" user "Package Geometry/Pastemask Bottom")
		(5 "F.SilkS" user "Ref Des/Silkscreen Top")
		(7 "B.SilkS" user "Ref Des/Silkscreen Bottom")
		(1 "F.Mask" user "Board Geometry/Soldermask Top")
		(3 "B.Mask" user "Board Geometry/Soldermask Bottom")
		(17 "Dwgs.User" user "User.Drawings")
		(19 "Cmts.User" user "User.Comments")
		(21 "Eco1.User" user "User.Eco1")
		(23 "Eco2.User" user "User.Eco2")
		(25 "Edge.Cuts" user "Board Geometry/Outline")
		(27 "Margin" user)
		(31 "F.CrtYd" user "Package Geometry/Place Bound Top")
		(29 "B.CrtYd" user "Package Geometry/Place Bound Bottom")
		(35 "F.Fab" user "Ref Des/Assembly Top")
		(33 "B.Fab" user "Ref Des/Assembly Bottom")
	)
	(footprint ""
		(layer "F.Cu")
		(at 77.999844 -478.300034)
		(property "Reference" "H13"
			(at -5.799582 -2.59334 0)
			(unlocked yes)
			(layer "F.SilkS")
			(effects
				(font
					(size 0.7874 0.5842)
					(thickness 0.1524)
				)
				(justify left)
			)
		)
		(property "Value" ""
			(at 0 0 0)
			(layer "F.Fab")
			(effects
				(font
					(size 1.27 1.27)
				)
			)
		)
		(duplicate_pad_numbers_are_jumpers no)
		(fp_line
			(start -3.4163 0)
			(end -3.4163 -0.4953)
			(stroke
				(width 0.1524)
				(type default)
			)
			(layer "F.SilkS")
		)
		(fp_line
			(start -3.4163 0.4953)
			(end -3.4163 0)
			(stroke
				(width 0.1524)
				(type default)
			)
			(layer "F.SilkS")
		)
		(fp_line
			(start 3.4163 -0.4953)
			(end 3.4163 0.4953)
			(stroke
				(width 0.1524)
				(type default)
			)
			(layer "F.SilkS")
		)
		(fp_arc
			(start -3.4163 -0.4953)
			(mid -2.415689 -2.910989)
			(end 0 -3.9116)
			(stroke
				(width 0.1524)
				(type default)
			)
			(layer "F.SilkS")
		)
		(fp_arc
			(start 0 -3.9116)
			(mid 2.415689 -2.910989)
			(end 3.4163 -0.4953)
			(stroke
				(width 0.1524)
				(type default)
			)
			(layer "F.SilkS")
		)
		(fp_arc
			(start 0 3.9116)
			(mid -2.415689 2.910989)
			(end -3.4163 0.4953)
			(stroke
				(width 0.1524)
				(type default)
			)
			(layer "F.SilkS")
		)
		(fp_arc
			(start 3.4163 0.4953)
			(mid 2.415689 2.910989)
			(end 0 3.9116)
			(stroke
				(width 0.1524)
				(type default)
			)
			(layer "F.SilkS")
		)
		(fp_line
			(start -3.4163 0)
			(end -3.4163 -0.4953)
			(stroke
				(width 0.1524)
				(type default)
			)
			(layer "B.SilkS")
		)
		(fp_line
			(start -3.4163 0.4953)
			(end -3.4163 0)
			(stroke
				(width 0.1524)
				(type default)
			)
			(layer "B.SilkS")
		)
		(fp_line
			(start 3.4163 -0.4953)
			(end 3.4163 0.4953)
			(stroke
				(width 0.1524)
				(type default)
			)
			(layer "B.SilkS")
		)
		(fp_arc
			(start -3.4163 -0.4953)
			(mid -2.415689 -2.910989)
			(end 0 -3.9116)
			(stroke
				(width 0.1524)
				(type default)
			)
			(layer "B.SilkS")
		)
		(fp_arc
			(start 0 -3.9116)
			(mid 2.415689 -2.910989)
			(end 3.4163 -0.4953)
			(stroke
				(width 0.1524)
				(type default)
			)
			(layer "B.SilkS")
		)
		(fp_arc
			(start 0 3.9116)
			(mid -2.415689 2.910989)
			(end -3.4163 0.4953)
			(stroke
				(width 0.1524)
				(type default)
			)
			(layer "B.SilkS")
		)
		(fp_arc
			(start 3.4163 0.4953)
			(mid 2.415689 2.910989)
			(end 0 3.9116)
			(stroke
				(width 0.1524)
				(type default)
			)
			(layer "B.SilkS")
		)
		(fp_poly
			(pts
				(arc
					(start -2.853944 -0.499872)
					(mid 0 -3.353816)
					(end 2.853944 -0.499872)
				)
				(arc
					(start 2.853944 0.499872)
					(mid 0 3.35407)
					(end -2.853944 0.499872)
				)
			)
			(stroke
				(width 0)
				(type default)
			)
			(fill no)
			(layer "B.CrtYd")
		)
		(fp_poly
			(pts
				(arc
					(start -2.853944 -0.499872)
					(mid 0 -3.353816)
					(end 2.853944 -0.499872)
				)
				(arc
					(start 2.853944 0.499872)
					(mid 0 3.35407)
					(end -2.853944 0.499872)
				)
			)
			(stroke
				(width 0)
				(type default)
			)
			(fill no)
			(layer "F.CrtYd")
		)
		(pad "" np_thru_hole oval
			(at 0 0)
			(size 5.207 6.1976)
			(drill oval 5.207 6.1976)
			(layers "*.Cu" "*.Mask")
			(clearance 0.381)
			(thermal_gap 0.381)
		)
		(zone
			(layers "F.Cu" "B.Cu" "In1.Cu" "In2.Cu" "In3.Cu" "In4.Cu" "In5.Cu" "In6.Cu")
			(hatch none 0.5)
			(connect_pads
				(clearance 0)
			)
			(min_thickness 0.25)
			(keepout
				(tracks not_allowed)
				(vias allowed)
				(pads allowed)
				(copperpour not_allowed)
				(footprints allowed)
			)
			(placement
				(enabled no)
				(sheetname "")
			)
			(fill
				(thermal_gap 0.5)
				(thermal_bridge_width 0.5)
				(island_removal_mode 0)
			)
			(polygon
				(pts
					(xy 74.888344 -478.300034)
					(arc
						(start 74.888344 -478.795334)
						(mid 75.799681 -480.995497)
						(end 77.999844 -481.906834)
					)
					(arc
						(start 77.999844 -481.906834)
						(mid 80.200007 -480.995497)
						(end 81.111344 -478.795334)
					)
					(arc
						(start 81.111344 -477.804734)
						(mid 80.200007 -475.604571)
						(end 77.999844 -474.693234)
					)
					(arc
						(start 77.999844 -474.693234)
						(mid 75.799681 -475.604571)
						(end 74.888344 -477.804734)
					)
				)
			)
		)
	)
	(footprint ""
		(layer "F.Cu")
		(at 50.478944 -329.972416 180)
		(property "Reference" "CE15"
			(at 1.661922 5.89026 0)
			(unlocked yes)
			(layer "F.SilkS")
			(effects
				(font
					(size 0.7874 0.5842)
					(thickness 0.1524)
				)
				(justify left)
			)
		)
		(property "Value" ""
			(at 0 0 180)
			(layer "F.Fab")
			(effects
				(font
					(size 1.27 1.27)
				)
			)
		)
		(duplicate_pad_numbers_are_jumpers no)
		(fp_line
			(start 0 -4.2672)
			(end 0 4.2672)
			(stroke
				(width 0.1524)
				(type default)
			)
			(layer "F.SilkS")
		)
		(fp_circle
			(center 0 0)
			(end -4.2672 0)
			(stroke
				(width 0.1524)
				(type default)
			)
			(fill no)
			(layer "F.SilkS")
		)
		(fp_poly
			(pts
				(arc
					(start 0 -4.2672)
					(mid 4.2672 0)
					(end 0 4.2672)
				)
			)
			(stroke
				(width 0)
				(type default)
			)
			(fill yes)
			(layer "F.SilkS")
		)
		(fp_poly
			(pts
				(xy -2.5146 -0.762) (xy -0.9906 -0.762) (xy -0.9906 0.762) (xy -2.5146 0.762)
			)
			(stroke
				(width 0)
				(type default)
			)
			(fill no)
			(layer "B.CrtYd")
		)
		(fp_poly
			(pts
				(arc
					(start 1.7526 0.762)
					(mid 2.291415 -0.538815)
					(end 0.9906 0)
				)
				(arc
					(start 0.9906 0.0254)
					(mid 1.206345 0.546255)
					(end 1.7272 0.762)
				)
			)
			(stroke
				(width 0)
				(type default)
			)
			(fill no)
			(layer "B.CrtYd")
		)
		(fp_poly
			(pts
				(arc
					(start -4.2672 0)
					(mid 4.2672 0)
					(end -4.2672 0)
				)
			)
			(stroke
				(width 0)
				(type default)
			)
			(fill no)
			(layer "F.CrtYd")
		)
		(fp_circle
			(center 0 0)
			(end -4.2672 0)
			(stroke
				(width 0.1)
				(type default)
			)
			(fill no)
			(layer "F.Fab")
		)
		(fp_text user "+"
			(at -5.080762 -0.360426 180)
			(unlocked yes)
			(layer "F.SilkS")
			(effects
				(font
					(size 0.7874 0.5842)
					(thickness 0.1524)
				)
				(justify left)
			)
		)
		(fp_text user "+"
			(at -5.6642 -0.34925 180)
			(unlocked yes)
			(layer "F.Fab")
			(effects
				(font
					(size 1.905 1.4224)
					(thickness 0.000001)
				)
				(justify left)
			)
		)
		(pad "1" thru_hole rect
			(at -1.75006 0 180)
			(size 1.397 1.397)
			(drill 0.9144)
			(layers "*.Cu" "*.Mask")
			(remove_unused_layers no)
			(net "P12V")
			(clearance 0.0127)
			(thermal_gap 0.0127)
			(padstack
				(mode front_inner_back)
				(layer "Inner"
					(shape circle)
					(size 1.397 1.397)
					(clearance 0.0127)
				)
				(layer "B.Cu"
					(shape rect)
					(size 1.397 1.397)
					(clearance 0.0127)
				)
			)
		)
		(pad "2" thru_hole circle
			(at 1.75006 0 180)
			(size 1.397 1.397)
			(drill 0.9144)
			(layers "*.Cu" "*.Mask")
			(remove_unused_layers no)
			(net "GND")
			(clearance 0.0127)
			(thermal_gap 0.0127)
		)
	)
	(footprint ""
		(layer "F.Cu")
		(at 26.226008 -453.535034)
		(property "Reference" "R60"
			(at -3.597402 -0.121666 0)
			(unlocked yes)
			(layer "F.SilkS")
			(effects
				(font
					(size 0.7874 0.5842)
					(thickness 0.1524)
				)
				(justify left)
			)
		)
		(property "Value" ""
			(at 0 0 0)
			(layer "F.Fab")
			(effects
				(font
					(size 1.27 1.27)
				)
			)
		)
		(duplicate_pad_numbers_are_jumpers no)
		(fp_line
			(start -0.7874 -0.4064)
			(end 0.7874 -0.4064)
			(stroke
				(width 0.1524)
				(type default)
			)
			(layer "F.SilkS")
		)
		(fp_line
			(start -0.7874 0.4064)
			(end -0.7874 -0.4064)
			(stroke
				(width 0.1524)
				(type default)
			)
			(layer "F.SilkS")
		)
		(fp_line
			(start 0.7874 -0.4064)
			(end 0.7874 0.4064)
			(stroke
				(width 0.1524)
				(type default)
			)
			(layer "F.SilkS")
		)
		(fp_line
			(start 0.7874 0.4064)
			(end -0.7874 0.4064)
			(stroke
				(width 0.1524)
				(type default)
			)
			(layer "F.SilkS")
		)
		(fp_poly
			(pts
				(xy -0.508 0.2794) (xy -0.508 0.2286) (xy -0.635 0.2286) (xy -0.635 -0.254) (xy -0.5334 -0.254)
				(xy -0.5334 -0.2794) (xy 0.5334 -0.2794) (xy 0.5334 -0.254) (xy 0.635 -0.254) (xy 0.635 0.254) (xy 0.5334 0.254)
				(xy 0.5334 0.2794)
			)
			(stroke
				(width 0)
				(type default)
			)
			(fill no)
			(layer "F.CrtYd")
		)
		(pad "1" smd rect
			(at 0.40005 0)
			(size 0.4572 0.508)
			(layers "F.Cu" "F.Mask" "F.Paste")
			(net "PSU6_PS_KILL")
		)
		(pad "2" smd rect
			(at -0.40005 0)
			(size 0.4572 0.508)
			(layers "F.Cu" "F.Mask" "F.Paste")
			(net "GND")
		)
	)
	(footprint ""
		(layer "F.Cu")
		(at 50.100738 -62.882272 180)
		(property "Reference" "CE3"
			(at -4.025646 2.458974 0)
			(unlocked yes)
			(layer "F.SilkS")
			(effects
				(font
					(size 0.7874 0.5842)
					(thickness 0.1524)
				)
				(justify left)
			)
		)
		(property "Value" ""
			(at 0 0 180)
			(layer "F.Fab")
			(effects
				(font
					(size 1.27 1.27)
				)
			)
		)
		(duplicate_pad_numbers_are_jumpers no)
		(fp_line
			(start 0 -4.2672)
			(end 0 4.2672)
			(stroke
				(width 0.1524)
				(type default)
			)
			(layer "F.SilkS")
		)
		(fp_circle
			(center 0 0)
			(end -4.2672 0)
			(stroke
				(width 0.1524)
				(type default)
			)
			(fill no)
			(layer "F.SilkS")
		)
		(fp_poly
			(pts
				(arc
					(start 0 -4.2672)
					(mid 4.2672 0)
					(end 0 4.2672)
				)
			)
			(stroke
				(width 0)
				(type default)
			)
			(fill yes)
			(layer "F.SilkS")
		)
		(fp_poly
			(pts
				(xy -2.5146 -0.762) (xy -0.9906 -0.762) (xy -0.9906 0.762) (xy -2.5146 0.762)
			)
			(stroke
				(width 0)
				(type default)
			)
			(fill no)
			(layer "B.CrtYd")
		)
		(fp_poly
			(pts
				(arc
					(start 1.7526 0.762)
					(mid 2.291415 -0.538815)
					(end 0.9906 0)
				)
				(arc
					(start 0.9906 0.0254)
					(mid 1.206345 0.546255)
					(end 1.7272 0.762)
				)
			)
			(stroke
				(width 0)
				(type default)
			)
			(fill no)
			(layer "B.CrtYd")
		)
		(fp_poly
			(pts
				(arc
					(start -4.2672 0)
					(mid 4.2672 0)
					(end -4.2672 0)
				)
			)
			(stroke
				(width 0)
				(type default)
			)
			(fill no)
			(layer "F.CrtYd")
		)
		(fp_circle
			(center 0 0)
			(end -4.2672 0)
			(stroke
				(width 0.1)
				(type default)
			)
			(fill no)
			(layer "F.Fab")
		)
		(fp_text user "+"
			(at -5.750306 -0.11303 180)
			(unlocked yes)
			(layer "F.SilkS")
			(effects
				(font
					(size 0.7874 0.5842)
					(thickness 0.1524)
				)
				(justify left)
			)
		)
		(fp_text user "+"
			(at -5.6642 -0.34925 180)
			(unlocked yes)
			(layer "F.Fab")
			(effects
				(font
					(size 1.905 1.4224)
					(thickness 0.000001)
				)
				(justify left)
			)
		)
		(pad "1" thru_hole rect
			(at -1.75006 0 180)
			(size 1.397 1.397)
			(drill 0.9144)
			(layers "*.Cu" "*.Mask")
			(remove_unused_layers no)
			(net "P12V")
			(clearance 0.0127)
			(thermal_gap 0.0127)
			(padstack
				(mode front_inner_back)
				(layer "Inner"
					(shape circle)
					(size 1.397 1.397)
					(clearance 0.0127)
				)
				(layer "B.Cu"
					(shape rect)
					(size 1.397 1.397)
					(clearance 0.0127)
				)
			)
		)
		(pad "2" thru_hole circle
			(at 1.75006 0 180)
			(size 1.397 1.397)
			(drill 0.9144)
			(layers "*.Cu" "*.Mask")
			(remove_unused_layers no)
			(net "GND")
			(clearance 0.0127)
			(thermal_gap 0.0127)
		)
	)
	(footprint ""
		(layer "F.Cu")
		(at 46.472856 -247.282716 180)
		(property "Reference" "R96"
			(at -0.980186 -0.54483 0)
			(unlocked yes)
			(layer "F.SilkS")
			(effects
				(font
					(size 0.7874 0.5842)
					(thickness 0.1524)
				)
				(justify left)
			)
		)
		(property "Value" ""
			(at 0 0 180)
			(layer "F.Fab")
			(effects
				(font
					(size 1.27 1.27)
				)
			)
		)
		(duplicate_pad_numbers_are_jumpers no)
		(fp_line
			(start 0.7874 0.4064)
			(end -0.7874 0.4064)
			(stroke
				(width 0.1524)
				(type default)
			)
			(layer "F.SilkS")
		)
		(fp_line
			(start 0.7874 -0.4064)
			(end 0.7874 0.4064)
			(stroke
				(width 0.1524)
				(type default)
			)
			(layer "F.SilkS")
		)
		(fp_line
			(start -0.7874 0.4064)
			(end -0.7874 -0.4064)
			(stroke
				(width 0.1524)
				(type default)
			)
			(layer "F.SilkS")
		)
		(fp_line
			(start -0.7874 -0.4064)
			(end 0.7874 -0.4064)
			(stroke
				(width 0.1524)
				(type default)
			)
			(layer "F.SilkS")
		)
		(fp_poly
			(pts
				(xy -0.508 0.2794) (xy -0.508 0.2286) (xy -0.635 0.2286) (xy -0.635 -0.254) (xy -0.5334 -0.254)
				(xy -0.5334 -0.2794) (xy 0.5334 -0.2794) (xy 0.5334 -0.254) (xy 0.635 -0.254) (xy 0.635 0.254) (xy 0.5334 0.254)
				(xy 0.5334 0.2794)
			)
			(stroke
				(width 0)
				(type default)
			)
			(fill no)
			(layer "F.CrtYd")
		)
		(pad "1" smd rect
			(at 0.40005 0 180)
			(size 0.4572 0.508)
			(layers "F.Cu" "F.Mask" "F.Paste")
			(net "PSU3_REMOTE_R_P")
		)
		(pad "2" smd rect
			(at -0.40005 0 180)
			(size 0.4572 0.508)
			(layers "F.Cu" "F.Mask" "F.Paste")
			(net "P12V")
		)
	)
)
